# SCM (Grand Teton) — schematic netlist excerpt (pin names and nets, part order shuffled) for the footprints in the layout excerpt that follows; sources: Cadence DE-HDL packaged netlist, KiCad conversion of 12092022_DA0F0TMDCD0_F0T_Management_Board_D_brd_V3_OCP.brd

C164  Q_CAP  1UF 25V 10% X6S  pkg C0402  page 41 : A = VCCIO1 ; B = GND
R144  Q_RES  33.2 1% CHIP  pkg 0402LF  page 12 : A = SMB_BMC_MM12_R_SDA ; B = SMB_BMC_MM12_SDA

(kicad_pcb
	(version 20260206)
	(generator "pcbnew")
	(generator_version "10.0")
	(general
		(thickness 1.6)
		(legacy_teardrops no)
	)
	(paper "A4")
	(title_block
		(title "12092022_DA0F0TMDCD0_F0T_Management_Board_D_brd_V3_OCP.brd")
		(comment 1 "Grand Teton / footprints 1287-1288 of 1440")
	)
	(layers
		(0 "F.Cu" signal "TOP")
		(4 "In1.Cu" signal "GND")
		(6 "In2.Cu" signal "IN1")
		(8 "In3.Cu" signal "GND1")
		(10 "In4.Cu" signal "IN2")
		(12 "In5.Cu" signal "VCC")
		(14 "In6.Cu" signal "VCC1")
		(16 "In7.Cu" signal "IN3")
		(18 "In8.Cu" signal "GND2")
		(20 "In9.Cu" signal "IN4")
		(22 "In10.Cu" signal "GND3")
		(2 "B.Cu" signal "BOTTOM")
		(9 "F.Adhes" user "F.Adhesive")
		(11 "B.Adhes" user "B.Adhesive")
		(13 "F.Paste" user "Package Geometry/Pastemask Top")
		(15 "B.Paste" user "Package Geometry/Pastemask Bottom")
		(5 "F.SilkS" user "Ref Des/Silkscreen Top")
		(7 "B.SilkS" user "Ref Des/Silkscreen Bottom")
		(1 "F.Mask" user "Board Geometry/Soldermask Top")
		(3 "B.Mask" user "Board Geometry/Soldermask Bottom")
		(17 "Dwgs.User" user "User.Drawings")
		(19 "Cmts.User" user "User.Comments")
		(21 "Eco1.User" user "User.Eco1")
		(23 "Eco2.User" user "User.Eco2")
		(25 "Edge.Cuts" user "Board Geometry/Outline")
		(27 "Margin" user)
		(31 "F.CrtYd" user "Package Geometry/Place Bound Top")
		(29 "B.CrtYd" user "Package Geometry/Place Bound Bottom")
		(35 "F.Fab" user "Ref Des/Assembly Top")
		(33 "B.Fab" user "Ref Des/Assembly Bottom")
	)
	(footprint ""
		(layer "B.Cu")
		(at 19.459448 -92.787216 -90)
		(property "Reference" "C164"
			(at 0 0 90)
			(layer "B.SilkS")
			(hide yes)
			(effects
				(font
					(size 1.27 1.27)
				)
				(justify mirror)
			)
		)
		(property "Value" ""
			(at 0 0 90)
			(layer "B.Fab")
			(effects
				(font
					(size 1.27 1.27)
				)
				(justify mirror)
			)
		)
		(duplicate_pad_numbers_are_jumpers no)
		(fp_line
			(start -0.69215 0.2921)
			(end 0.69215 0.2921)
			(stroke
				(width 0.1524)
				(type default)
			)
			(layer "B.SilkS")
		)
		(fp_line
			(start 0.69215 0.2921)
			(end 0.69215 -0.2921)
			(stroke
				(width 0.1524)
				(type default)
			)
			(layer "B.SilkS")
		)
		(fp_line
			(start -0.69215 -0.2921)
			(end -0.69215 0.2921)
			(stroke
				(width 0.1524)
				(type default)
			)
			(layer "B.SilkS")
		)
		(fp_line
			(start 0.69215 -0.2921)
			(end -0.69215 -0.2921)
			(stroke
				(width 0.1524)
				(type default)
			)
			(layer "B.SilkS")
		)
		(fp_line
			(start -0.51435 0.2794)
			(end 0.51435 0.2794)
			(stroke
				(width 0.1)
				(type default)
			)
			(layer "B.Fab")
		)
		(fp_line
			(start 0.51435 0.2794)
			(end 0.51435 -0.2794)
			(stroke
				(width 0.1)
				(type default)
			)
			(layer "B.Fab")
		)
		(fp_line
			(start -0.51435 -0.2794)
			(end -0.51435 0.2794)
			(stroke
				(width 0.1)
				(type default)
			)
			(layer "B.Fab")
		)
		(fp_line
			(start 0.51435 -0.2794)
			(end -0.51435 -0.2794)
			(stroke
				(width 0.1)
				(type default)
			)
			(layer "B.Fab")
		)
		(pad "1" smd circle
			(at 0.40005 0 90)
			(size 0 0)
			(layers "B.Cu" "B.Mask" "B.Paste")
			(net "VCCIO1")
		)
		(pad "2" smd circle
			(at -0.40005 0 90)
			(size 0 0)
			(layers "B.Cu" "B.Mask" "B.Paste")
			(net "GND")
		)
		(zone
			(layer "B.Cu")
			(hatch none 0.5)
			(connect_pads
				(clearance 0)
			)
			(min_thickness 0.25)
			(keepout
				(tracks not_allowed)
				(vias allowed)
				(pads allowed)
				(copperpour not_allowed)
				(footprints allowed)
			)
			(placement
				(enabled no)
				(sheetname "")
			)
			(fill
				(thermal_gap 0.5)
				(thermal_bridge_width 0.5)
				(island_removal_mode 0)
			)
			(polygon
				(pts
					(xy 19.371818 -92.596716) (xy 19.313652 -92.688156) (xy 19.313652 -92.887546) (xy 19.371818 -92.977716)
					(xy 19.547078 -92.977716) (xy 19.605498 -92.887546) (xy 19.605498 -92.688156) (xy 19.547332 -92.596716)
				)
			)
		)
	)
	(footprint ""
		(layer "B.Cu")
		(at 41.966134 -46.16069)
		(property "Reference" "R144"
			(at 0 0 0)
			(layer "B.SilkS")
			(hide yes)
			(effects
				(font
					(size 1.27 1.27)
				)
				(justify mirror)
			)
		)
		(property "Value" ""
			(at 0 0 0)
			(layer "B.Fab")
			(effects
				(font
					(size 1.27 1.27)
				)
				(justify mirror)
			)
		)
		(duplicate_pad_numbers_are_jumpers no)
		(fp_line
			(start -0.7874 -0.4064)
			(end -0.7874 0.4064)
			(stroke
				(width 0.1524)
				(type default)
			)
			(layer "B.SilkS")
		)
		(fp_line
			(start -0.7874 0.4064)
			(end 0.7874 0.4064)
			(stroke
				(width 0.1524)
				(type default)
			)
			(layer "B.SilkS")
		)
		(fp_line
			(start 0.7874 -0.4064)
			(end -0.7874 -0.4064)
			(stroke
				(width 0.1524)
				(type default)
			)
			(layer "B.SilkS")
		)
		(fp_line
			(start 0.7874 0.4064)
			(end 0.7874 -0.4064)
			(stroke
				(width 0.1524)
				(type default)
			)
			(layer "B.SilkS")
		)
		(fp_line
			(start -0.67945 -0.3048)
			(end -0.67945 0.3048)
			(stroke
				(width 0.1)
				(type default)
			)
			(layer "B.Fab")
		)
		(fp_line
			(start -0.67945 0.3048)
			(end -0.120396 0.3048)
			(stroke
				(width 0.1)
				(type default)
			)
			(layer "B.Fab")
		)
		(fp_line
			(start -0.12065 -0.3048)
			(end -0.67945 -0.3048)
			(stroke
				(width 0.1)
				(type default)
			)
			(layer "B.Fab")
		)
		(fp_line
			(start -0.12065 -0.2794)
			(end -0.12065 -0.3048)
			(stroke
				(width 0.1)
				(type default)
			)
			(layer "B.Fab")
		)
		(fp_line
			(start -0.120396 0.2794)
			(end 0.12065 0.2794)
			(stroke
				(width 0.1)
				(type default)
			)
			(layer "B.Fab")
		)
		(fp_line
			(start -0.120396 0.3048)
			(end -0.120396 0.2794)
			(stroke
				(width 0.1)
				(type default)
			)
			(layer "B.Fab")
		)
		(fp_line
			(start 0.12065 -0.305054)
			(end 0.12065 -0.2794)
			(stroke
				(width 0.1)
				(type default)
			)
			(layer "B.Fab")
		)
		(fp_line
			(start 0.12065 -0.2794)
			(end -0.12065 -0.2794)
			(stroke
				(width 0.1)
				(type default)
			)
			(layer "B.Fab")
		)
		(fp_line
			(start 0.12065 0.2794)
			(end 0.12065 0.3048)
			(stroke
				(width 0.1)
				(type default)
			)
			(layer "B.Fab")
		)
		(fp_line
			(start 0.12065 0.3048)
			(end 0.67945 0.3048)
			(stroke
				(width 0.1)
				(type default)
			)
			(layer "B.Fab")
		)
		(fp_line
			(start 0.67945 -0.305054)
			(end 0.12065 -0.305054)
			(stroke
				(width 0.1)
				(type default)
			)
			(layer "B.Fab")
		)
		(fp_line
			(start 0.67945 0.3048)
			(end 0.67945 -0.305054)
			(stroke
				(width 0.1)
				(type default)
			)
			(layer "B.Fab")
		)
		(pad "1" smd circle
			(at 0.40005 0 180)
			(size 0 0)
			(layers "B.Cu" "B.Mask" "B.Paste")
			(net "SMB_BMC_MM12_R_SDA")
		)
		(pad "2" smd circle
			(at -0.40005 0 180)
			(size 0 0)
			(layers "B.Cu" "B.Mask" "B.Paste")
			(net "SMB_BMC_MM12_SDA")
		)
	)
)
